(kicad_pcb
	(version 20260206)
	(generator "pcbnew")
	(generator_version "10.0")
	(general
		(thickness 1.6)
		(legacy_teardrops no)
	)
	(paper "A4")
	(title_block
		(title "Bryce Canyon_F.DPB_16315-1-OCP.brd")
		(comment 1 "Bryce Canyon / footprints 1400-1404 of 2223")
	)
	(layers
		(0 "F.Cu" signal "TOP")
		(4 "In1.Cu" signal "L2GND")
		(6 "In2.Cu" signal "L3")
		(8 "In3.Cu" signal "L4GND")
		(10 "In4.Cu" signal "L5")
		(12 "In5.Cu" signal "L6VCC")
		(14 "In6.Cu" signal "L7VCC")
		(16 "In7.Cu" signal "L8")
		(18 "In8.Cu" signal "L9GND")
		(20 "In9.Cu" signal "L10")
		(22 "In10.Cu" signal "L11GND")
		(2 "B.Cu" signal "BOTTOM")
		(9 "F.Adhes" user "F.Adhesive")
		(11 "B.Adhes" user "B.Adhesive")
		(13 "F.Paste" user "Package Geometry/Pastemask Top")
		(15 "B.Paste" user "Package Geometry/Pastemask Bottom")
		(5 "F.SilkS" user "Ref Des/Silkscreen Top")
		(7 "B.SilkS" user "Ref Des/Silkscreen Bottom")
		(1 "F.Mask" user "Board Geometry/Soldermask Top")
		(3 "B.Mask" user "Board Geometry/Soldermask Bottom")
		(17 "Dwgs.User" user "User.Drawings")
		(19 "Cmts.User" user "User.Comments")
		(21 "Eco1.User" user "User.Eco1")
		(23 "Eco2.User" user "User.Eco2")
		(25 "Edge.Cuts" user "Board Geometry/Outline")
		(27 "Margin" user)
		(31 "F.CrtYd" user "Package Geometry/Place Bound Top")
		(29 "B.CrtYd" user "Package Geometry/Place Bound Bottom")
		(35 "F.Fab" user "Ref Des/Assembly Top")
		(33 "B.Fab" user "Ref Des/Assembly Bottom")
	)
	(footprint ""
		(layer "F.Cu")
		(at 22.996398 -278.554942 90)
		(property "Reference" "R970"
			(at 0 0 90)
			(layer "F.SilkS")
			(hide yes)
			(effects
				(font
					(size 1.27 1.27)
				)
			)
		)
		(property "Value" "4K7R2J-2-GP"
			(at 0.064008 -3.993896 90)
			(unlocked yes)
			(layer "F.Fab")
			(hide yes)
			(effects
				(font
					(size 1.016 1.016)
					(thickness 0.1524)
				)
			)
		)
		(property "Device Type" "R402H16"
			(at 0.064008 -5.517896 90)
			(unlocked yes)
			(layer "F.Fab")
			(hide yes)
			(effects
				(font
					(size 1.016 1.016)
					(thickness 0.1524)
				)
			)
		)
		(duplicate_pad_numbers_are_jumpers no)
		(fp_line
			(start 0.508 -0.9398)
			(end -0.508 -0.9398)
			(stroke
				(width 0.1524)
				(type default)
			)
			(layer "F.SilkS")
		)
		(fp_line
			(start -0.508 -0.9398)
			(end -0.508 0.9398)
			(stroke
				(width 0.1524)
				(type default)
			)
			(layer "F.SilkS")
		)
		(fp_rect
			(start -0.508 0.9398)
			(end 0.508 -0.9398)
			(stroke
				(width 0)
				(type default)
			)
			(fill no)
			(layer "F.CrtYd")
		)
		(fp_rect
			(start -0.508 0.9398)
			(end 0.508 -0.9398)
			(stroke
				(width 0)
				(type default)
			)
			(fill no)
			(layer "F.Fab")
		)
		(pad "1" smd custom
			(at 0 -0.4445 90)
			(size 0.1397 0.1397)
			(layers "F.Cu" "F.Mask" "F.Paste")
			(net "SW_PWR_R_HDD0")
			(options
				(clearance outline)
				(anchor circle)
			)
			(primitives
				(gr_poly
					(pts
						(arc
							(start -0.1778 -0.2794)
							(mid -0.249642 -0.249642)
							(end -0.2794 -0.1778)
						)
						(arc
							(start -0.2794 0.1778)
							(mid -0.249642 0.249642)
							(end -0.1778 0.2794)
						)
						(arc
							(start 0.1778 0.2794)
							(mid 0.249642 0.249642)
							(end 0.2794 0.1778)
						)
						(arc
							(start 0.2794 -0.1778)
							(mid 0.249642 -0.249642)
							(end 0.1778 -0.2794)
						)
					)
					(width 0)
					(fill yes)
				)
			)
		)
		(pad "2" smd custom
			(at 0 0.4445 90)
			(size 0.1397 0.1397)
			(layers "F.Cu" "F.Mask" "F.Paste")
			(net "GND")
			(options
				(clearance outline)
				(anchor circle)
			)
			(primitives
				(gr_poly
					(pts
						(arc
							(start -0.1778 -0.2794)
							(mid -0.249642 -0.249642)
							(end -0.2794 -0.1778)
						)
						(arc
							(start -0.2794 0.1778)
							(mid -0.249642 0.249642)
							(end -0.1778 0.2794)
						)
						(arc
							(start 0.1778 0.2794)
							(mid 0.249642 0.249642)
							(end 0.2794 0.1778)
						)
						(arc
							(start 0.2794 -0.1778)
							(mid 0.249642 -0.249642)
							(end 0.1778 -0.2794)
						)
					)
					(width 0)
					(fill yes)
				)
			)
		)
	)
	(footprint ""
		(layer "F.Cu")
		(at 180.7464 -276.014942 -90)
		(property "Reference" "R253"
			(at 0 0 270)
			(layer "F.SilkS")
			(hide yes)
			(effects
				(font
					(size 1.27 1.27)
				)
			)
		)
		(property "Value" "1KR2F-3-GP"
			(at 0.064008 -3.993896 270)
			(unlocked yes)
			(layer "F.Fab")
			(hide yes)
			(effects
				(font
					(size 1.016 1.016)
					(thickness 0.1524)
				)
			)
		)
		(property "Device Type" "R402H16"
			(at 0.064008 -5.517896 270)
			(unlocked yes)
			(layer "F.Fab")
			(hide yes)
			(effects
				(font
					(size 1.016 1.016)
					(thickness 0.1524)
				)
			)
		)
		(duplicate_pad_numbers_are_jumpers no)
		(fp_line
			(start -0.508 -0.9398)
			(end -0.508 0.9398)
			(stroke
				(width 0.1524)
				(type default)
			)
			(layer "F.SilkS")
		)
		(fp_line
			(start 0.508 -0.9398)
			(end -0.508 -0.9398)
			(stroke
				(width 0.1524)
				(type default)
			)
			(layer "F.SilkS")
		)
		(fp_rect
			(start -0.508 0.9398)
			(end 0.508 -0.9398)
			(stroke
				(width 0)
				(type default)
			)
			(fill no)
			(layer "F.CrtYd")
		)
		(fp_rect
			(start -0.508 0.9398)
			(end 0.508 -0.9398)
			(stroke
				(width 0)
				(type default)
			)
			(fill no)
			(layer "F.Fab")
		)
		(pad "1" smd custom
			(at 0 -0.4445 270)
			(size 0.1397 0.1397)
			(layers "F.Cu" "F.Mask" "F.Paste")
			(net "P3V3_STBY_A")
			(options
				(clearance outline)
				(anchor circle)
			)
			(primitives
				(gr_poly
					(pts
						(arc
							(start -0.1778 -0.2794)
							(mid -0.249642 -0.249642)
							(end -0.2794 -0.1778)
						)
						(arc
							(start -0.2794 0.1778)
							(mid -0.249642 0.249642)
							(end -0.1778 0.2794)
						)
						(arc
							(start 0.1778 0.2794)
							(mid 0.249642 0.249642)
							(end 0.2794 0.1778)
						)
						(arc
							(start 0.2794 -0.1778)
							(mid 0.249642 -0.249642)
							(end 0.1778 -0.2794)
						)
					)
					(width 0)
					(fill yes)
				)
			)
		)
		(pad "2" smd custom
			(at 0 0.4445 270)
			(size 0.1397 0.1397)
			(layers "F.Cu" "F.Mask" "F.Paste")
			(net "SW_PWR_R_HDD5")
			(options
				(clearance outline)
				(anchor circle)
			)
			(primitives
				(gr_poly
					(pts
						(arc
							(start -0.1778 -0.2794)
							(mid -0.249642 -0.249642)
							(end -0.2794 -0.1778)
						)
						(arc
							(start -0.2794 0.1778)
							(mid -0.249642 0.249642)
							(end -0.1778 0.2794)
						)
						(arc
							(start 0.1778 0.2794)
							(mid 0.249642 0.249642)
							(end 0.2794 0.1778)
						)
						(arc
							(start 0.2794 -0.1778)
							(mid 0.249642 -0.249642)
							(end 0.1778 -0.2794)
						)
					)
					(width 0)
					(fill yes)
				)
			)
		)
	)
	(footprint ""
		(layer "F.Cu")
		(at 51.943 -163.576 90)
		(property "Reference" "C217"
			(at 0 0 90)
			(layer "F.SilkS")
			(hide yes)
			(effects
				(font
					(size 1.27 1.27)
				)
			)
		)
		(property "Value" "SCD033U25V2KX-GP"
			(at 1.1811 -2.7051 90)
			(unlocked yes)
			(layer "F.Fab")
			(hide yes)
			(effects
				(font
					(size 1.016 1.016)
					(thickness 0.1524)
				)
			)
		)
		(property "Device Type" "C402H22"
			(at 1.1811 -4.2291 90)
			(unlocked yes)
			(layer "F.Fab")
			(hide yes)
			(effects
				(font
					(size 1.016 1.016)
					(thickness 0.1524)
				)
			)
		)
		(duplicate_pad_numbers_are_jumpers no)
		(fp_rect
			(start -0.4318 0.9525)
			(end 0.4318 -0.9525)
			(stroke
				(width 0)
				(type default)
			)
			(fill no)
			(layer "F.CrtYd")
		)
		(fp_rect
			(start -0.4318 0.9525)
			(end 0.4318 -0.9525)
			(stroke
				(width 0)
				(type default)
			)
			(fill no)
			(layer "F.Fab")
		)
		(pad "1" smd custom
			(at 0 -0.4445 90)
			(size 0.1524 0.1524)
			(layers "F.Cu" "F.Mask" "F.Paste")
			(net "SW_HDD_P13")
			(options
				(clearance outline)
				(anchor circle)
			)
			(primitives
				(gr_poly
					(pts
						(arc
							(start 0.3048 -0.2032)
							(mid 0.275042 -0.275042)
							(end 0.2032 -0.3048)
						)
						(arc
							(start -0.2032 -0.3048)
							(mid -0.275042 -0.275042)
							(end -0.3048 -0.2032)
						)
						(arc
							(start -0.3048 0.2032)
							(mid -0.275042 0.275042)
							(end -0.2032 0.3048)
						)
						(arc
							(start 0.2032 0.3048)
							(mid 0.275042 0.275042)
							(end 0.3048 0.2032)
						)
					)
					(width 0)
					(fill yes)
				)
			)
		)
		(pad "2" smd custom
			(at 0 0.4445 90)
			(size 0.1524 0.1524)
			(layers "F.Cu" "F.Mask" "F.Paste")
			(net "GND")
			(options
				(clearance outline)
				(anchor circle)
			)
			(primitives
				(gr_poly
					(pts
						(arc
							(start 0.3048 -0.2032)
							(mid 0.275042 -0.275042)
							(end 0.2032 -0.3048)
						)
						(arc
							(start -0.2032 -0.3048)
							(mid -0.275042 -0.275042)
							(end -0.3048 -0.2032)
						)
						(arc
							(start -0.3048 0.2032)
							(mid -0.275042 0.275042)
							(end -0.2032 0.3048)
						)
						(arc
							(start 0.2032 0.3048)
							(mid 0.275042 0.275042)
							(end 0.3048 0.2032)
						)
					)
					(width 0)
					(fill yes)
				)
			)
		)
	)
	(footprint ""
		(layer "F.Cu")
		(at 368.481102 -160.735518 180)
		(property "Reference" "R581"
			(at 0 0 180)
			(layer "F.SilkS")
			(hide yes)
			(effects
				(font
					(size 1.27 1.27)
				)
			)
		)
		(property "Value" "4K7R2J-2-GP"
			(at 0.064008 -3.993896 180)
			(unlocked yes)
			(layer "F.Fab")
			(hide yes)
			(effects
				(font
					(size 1.016 1.016)
					(thickness 0.1524)
				)
			)
		)
		(property "Device Type" "R402H16"
			(at 0.064008 -5.517896 180)
			(unlocked yes)
			(layer "F.Fab")
			(hide yes)
			(effects
				(font
					(size 1.016 1.016)
					(thickness 0.1524)
				)
			)
		)
		(duplicate_pad_numbers_are_jumpers no)
		(fp_line
			(start 0.508 -0.9398)
			(end -0.508 -0.9398)
			(stroke
				(width 0.1524)
				(type default)
			)
			(layer "F.SilkS")
		)
		(fp_line
			(start -0.508 -0.9398)
			(end -0.508 0.9398)
			(stroke
				(width 0.1524)
				(type default)
			)
			(layer "F.SilkS")
		)
		(fp_rect
			(start -0.508 0.9398)
			(end 0.508 -0.9398)
			(stroke
				(width 0)
				(type default)
			)
			(fill no)
			(layer "F.CrtYd")
		)
		(fp_rect
			(start -0.508 0.9398)
			(end 0.508 -0.9398)
			(stroke
				(width 0)
				(type default)
			)
			(fill no)
			(layer "F.Fab")
		)
		(pad "1" smd custom
			(at 0 -0.4445 180)
			(size 0.1397 0.1397)
			(layers "F.Cu" "F.Mask" "F.Paste")
			(net "P12V_A")
			(options
				(clearance outline)
				(anchor circle)
			)
			(primitives
				(gr_poly
					(pts
						(arc
							(start -0.1778 -0.2794)
							(mid -0.249642 -0.249642)
							(end -0.2794 -0.1778)
						)
						(arc
							(start -0.2794 0.1778)
							(mid -0.249642 0.249642)
							(end -0.1778 0.2794)
						)
						(arc
							(start 0.1778 0.2794)
							(mid 0.249642 0.249642)
							(end 0.2794 0.1778)
						)
						(arc
							(start 0.2794 -0.1778)
							(mid 0.249642 -0.249642)
							(end 0.1778 -0.2794)
						)
					)
					(width 0)
					(fill yes)
				)
			)
		)
		(pad "2" smd custom
			(at 0 0.4445 180)
			(size 0.1397 0.1397)
			(layers "F.Cu" "F.Mask" "F.Paste")
			(net "SW_HDD_R19")
			(options
				(clearance outline)
				(anchor circle)
			)
			(primitives
				(gr_poly
					(pts
						(arc
							(start -0.1778 -0.2794)
							(mid -0.249642 -0.249642)
							(end -0.2794 -0.1778)
						)
						(arc
							(start -0.2794 0.1778)
							(mid -0.249642 0.249642)
							(end -0.1778 0.2794)
						)
						(arc
							(start 0.1778 0.2794)
							(mid 0.249642 0.249642)
							(end 0.2794 0.1778)
						)
						(arc
							(start 0.2794 -0.1778)
							(mid 0.249642 -0.249642)
							(end 0.1778 -0.2794)
						)
					)
					(width 0)
					(fill yes)
				)
			)
		)
	)
	(footprint ""
		(layer "F.Cu")
		(at 181.483 -177.270918)
		(property "Reference" "R520"
			(at 0 0 0)
			(layer "F.SilkS")
			(hide yes)
			(effects
				(font
					(size 1.27 1.27)
				)
			)
		)
		(property "Value" "2R6F-GP"
			(at -0.0508 -4.8514 0)
			(unlocked yes)
			(layer "F.Fab")
			(hide yes)
			(effects
				(font
					(size 1.016 1.016)
					(thickness 0.1524)
				)
			)
		)
		(property "Device Type" "R1206H26"
			(at 0 -6.3754 0)
			(unlocked yes)
			(layer "F.Fab")
			(hide yes)
			(effects
				(font
					(size 1.016 1.016)
					(thickness 0.1524)
				)
			)
		)
		(duplicate_pad_numbers_are_jumpers no)
		(fp_line
			(start -1.016 -2.2352)
			(end 1.016 -2.2352)
			(stroke
				(width 0.1524)
				(type default)
			)
			(layer "F.SilkS")
		)
		(fp_line
			(start -1.016 2.2352)
			(end -1.016 -2.2352)
			(stroke
				(width 0.1524)
				(type default)
			)
			(layer "F.SilkS")
		)
		(fp_line
			(start 1.016 -2.2352)
			(end 1.016 2.2352)
			(stroke
				(width 0.1524)
				(type default)
			)
			(layer "F.SilkS")
		)
		(fp_line
			(start 1.016 2.2352)
			(end -1.016 2.2352)
			(stroke
				(width 0.1524)
				(type default)
			)
			(layer "F.SilkS")
		)
		(fp_rect
			(start -1.0922 2.3114)
			(end 1.0922 -2.3114)
			(stroke
				(width 0)
				(type default)
			)
			(fill no)
			(layer "F.CrtYd")
		)
		(fp_poly
			(pts
				(xy -1.0922 -2.3114) (xy 1.0922 -2.3114) (xy 1.0922 2.3114) (xy -1.0922 2.3114)
			)
			(stroke
				(width 0)
				(type default)
			)
			(fill no)
			(layer "F.Fab")
		)
		(pad "1" smd rect
			(at 0 -1.397)
			(size 1.651 1.27)
			(layers "F.Cu" "F.Mask" "F.Paste")
			(net "P5V_HDD17")
		)
		(pad "2" smd rect
			(at 0 1.397)
			(size 1.651 1.27)
			(layers "F.Cu" "F.Mask" "F.Paste")
			(net "5V_PRE_17")
		)
	)
)
